# T6G (Grand Teton) — schematic netlist excerpt (pin names and nets, part order shuffled) for the footprints in the layout excerpt that follows; sources: Cadence DE-HDL packaged netlist, KiCad conversion of 04192023_DAF0TMB3IC0_F0TG_MB_C_brd_V02_OCP.brd

R8043  Q_RES  1K 1% EMPTY  pkg 0402LF  page 200 : A = PVDD18_S5_P0 ; B = SVID_PVDDCR_CPU1_P0_SVTO
C577  Q_CAP  1UF 4V 20% X6S  pkg 0201  page 279 : A = P0V9_CPU0_RT0_2A ; B = GND
PR183  Q_RES  1 1% CHIP  pkg 0402LF  page 210 : A = PVDDCR_CPU0_P1_VCC ; B = P3V3_AUX

(kicad_pcb
	(version 20260206)
	(generator "pcbnew")
	(generator_version "10.0")
	(general
		(thickness 1.6)
		(legacy_teardrops no)
	)
	(paper "A4")
	(title_block
		(title "04192023_DAF0TMB3IC0_F0TG_MB_C_brd_V02_OCP.brd")
		(comment 1 "Grand Teton / footprints 5339-5341 of 8354")
	)
	(layers
		(0 "F.Cu" signal "TOP")
		(4 "In1.Cu" signal "GND")
		(6 "In2.Cu" signal "IN1")
		(8 "In3.Cu" signal "GND1")
		(10 "In4.Cu" signal "IN2")
		(12 "In5.Cu" signal "GND2")
		(14 "In6.Cu" signal "IN3")
		(16 "In7.Cu" signal "GND3")
		(18 "In8.Cu" signal "VCC")
		(20 "In9.Cu" signal "VCC1")
		(22 "In10.Cu" signal "GND4")
		(24 "In11.Cu" signal "IN4")
		(26 "In12.Cu" signal "GND5")
		(28 "In13.Cu" signal "IN5")
		(30 "In14.Cu" signal "GND6")
		(32 "In15.Cu" signal "IN6")
		(34 "In16.Cu" signal "GND7")
		(2 "B.Cu" signal "BOTTOM")
		(9 "F.Adhes" user "F.Adhesive")
		(11 "B.Adhes" user "B.Adhesive")
		(13 "F.Paste" user "Package Geometry/Pastemask Top")
		(15 "B.Paste" user "Package Geometry/Pastemask Bottom")
		(5 "F.SilkS" user "Ref Des/Silkscreen Top")
		(7 "B.SilkS" user "Ref Des/Silkscreen Bottom")
		(1 "F.Mask" user "Board Geometry/Soldermask Top")
		(3 "B.Mask" user "Board Geometry/Soldermask Bottom")
		(17 "Dwgs.User" user "User.Drawings")
		(19 "Cmts.User" user "User.Comments")
		(21 "Eco1.User" user "User.Eco1")
		(23 "Eco2.User" user "User.Eco2")
		(25 "Edge.Cuts" user "Board Geometry/Outline")
		(27 "Margin" user)
		(31 "F.CrtYd" user "Package Geometry/Place Bound Top")
		(29 "B.CrtYd" user "Package Geometry/Place Bound Bottom")
		(35 "F.Fab" user "Ref Des/Assembly Top")
		(33 "B.Fab" user "Ref Des/Assembly Bottom")
	)
	(footprint ""
		(layer "B.Cu")
		(at 102.528878 -139.93241 90)
		(property "Reference" "PR183"
			(at 0 0 90)
			(layer "B.SilkS")
			(hide yes)
			(effects
				(font
					(size 1.27 1.27)
				)
				(justify mirror)
			)
		)
		(property "Value" ""
			(at 0 0 90)
			(layer "B.Fab")
			(effects
				(font
					(size 1.27 1.27)
				)
				(justify mirror)
			)
		)
		(duplicate_pad_numbers_are_jumpers no)
		(fp_line
			(start 0.7874 -0.4064)
			(end -0.7874 -0.4064)
			(stroke
				(width 0.1524)
				(type default)
			)
			(layer "B.SilkS")
		)
		(fp_line
			(start -0.7874 -0.4064)
			(end -0.7874 0.4064)
			(stroke
				(width 0.1524)
				(type default)
			)
			(layer "B.SilkS")
		)
		(fp_line
			(start 0.7874 0.4064)
			(end 0.7874 -0.4064)
			(stroke
				(width 0.1524)
				(type default)
			)
			(layer "B.SilkS")
		)
		(fp_line
			(start -0.7874 0.4064)
			(end 0.7874 0.4064)
			(stroke
				(width 0.1524)
				(type default)
			)
			(layer "B.SilkS")
		)
		(fp_line
			(start 0.67945 -0.305054)
			(end 0.12065 -0.305054)
			(stroke
				(width 0.1)
				(type default)
			)
			(layer "B.Fab")
		)
		(fp_line
			(start 0.12065 -0.305054)
			(end 0.12065 -0.2794)
			(stroke
				(width 0.1)
				(type default)
			)
			(layer "B.Fab")
		)
		(fp_line
			(start -0.12065 -0.3048)
			(end -0.67945 -0.3048)
			(stroke
				(width 0.1)
				(type default)
			)
			(layer "B.Fab")
		)
		(fp_line
			(start -0.67945 -0.3048)
			(end -0.67945 0.3048)
			(stroke
				(width 0.1)
				(type default)
			)
			(layer "B.Fab")
		)
		(fp_line
			(start 0.12065 -0.2794)
			(end -0.12065 -0.2794)
			(stroke
				(width 0.1)
				(type default)
			)
			(layer "B.Fab")
		)
		(fp_line
			(start -0.12065 -0.2794)
			(end -0.12065 -0.3048)
			(stroke
				(width 0.1)
				(type default)
			)
			(layer "B.Fab")
		)
		(fp_line
			(start 0.12065 0.2794)
			(end 0.12065 0.3048)
			(stroke
				(width 0.1)
				(type default)
			)
			(layer "B.Fab")
		)
		(fp_line
			(start -0.120396 0.2794)
			(end 0.12065 0.2794)
			(stroke
				(width 0.1)
				(type default)
			)
			(layer "B.Fab")
		)
		(fp_line
			(start 0.67945 0.3048)
			(end 0.67945 -0.305054)
			(stroke
				(width 0.1)
				(type default)
			)
			(layer "B.Fab")
		)
		(fp_line
			(start 0.12065 0.3048)
			(end 0.67945 0.3048)
			(stroke
				(width 0.1)
				(type default)
			)
			(layer "B.Fab")
		)
		(fp_line
			(start -0.120396 0.3048)
			(end -0.120396 0.2794)
			(stroke
				(width 0.1)
				(type default)
			)
			(layer "B.Fab")
		)
		(fp_line
			(start -0.67945 0.3048)
			(end -0.120396 0.3048)
			(stroke
				(width 0.1)
				(type default)
			)
			(layer "B.Fab")
		)
		(pad "1" smd circle
			(at 0.40005 0 270)
			(size 0 0)
			(layers "B.Cu" "B.Mask" "B.Paste")
			(net "PVDDCR_CPU0_P1_VCC")
		)
		(pad "2" smd circle
			(at -0.40005 0 270)
			(size 0 0)
			(layers "B.Cu" "B.Mask" "B.Paste")
			(net "P3V3_AUX")
		)
	)
	(footprint ""
		(layer "B.Cu")
		(at 302.133 -355.854 180)
		(property "Reference" "R8043"
			(at 0 0 0)
			(layer "B.SilkS")
			(hide yes)
			(effects
				(font
					(size 1.27 1.27)
				)
				(justify mirror)
			)
		)
		(property "Value" ""
			(at 0 0 0)
			(layer "B.Fab")
			(effects
				(font
					(size 1.27 1.27)
				)
				(justify mirror)
			)
		)
		(duplicate_pad_numbers_are_jumpers no)
		(fp_line
			(start 0.7874 0.4064)
			(end 0.7874 -0.4064)
			(stroke
				(width 0.1524)
				(type default)
			)
			(layer "B.SilkS")
		)
		(fp_line
			(start 0.7874 -0.4064)
			(end -0.7874 -0.4064)
			(stroke
				(width 0.1524)
				(type default)
			)
			(layer "B.SilkS")
		)
		(fp_line
			(start -0.7874 0.4064)
			(end 0.7874 0.4064)
			(stroke
				(width 0.1524)
				(type default)
			)
			(layer "B.SilkS")
		)
		(fp_line
			(start -0.7874 -0.4064)
			(end -0.7874 0.4064)
			(stroke
				(width 0.1524)
				(type default)
			)
			(layer "B.SilkS")
		)
		(fp_line
			(start 0.67945 0.3048)
			(end 0.67945 -0.305054)
			(stroke
				(width 0.1)
				(type default)
			)
			(layer "B.Fab")
		)
		(fp_line
			(start 0.67945 -0.305054)
			(end 0.12065 -0.305054)
			(stroke
				(width 0.1)
				(type default)
			)
			(layer "B.Fab")
		)
		(fp_line
			(start 0.12065 0.3048)
			(end 0.67945 0.3048)
			(stroke
				(width 0.1)
				(type default)
			)
			(layer "B.Fab")
		)
		(fp_line
			(start 0.12065 0.2794)
			(end 0.12065 0.3048)
			(stroke
				(width 0.1)
				(type default)
			)
			(layer "B.Fab")
		)
		(fp_line
			(start 0.12065 -0.2794)
			(end -0.12065 -0.2794)
			(stroke
				(width 0.1)
				(type default)
			)
			(layer "B.Fab")
		)
		(fp_line
			(start 0.12065 -0.305054)
			(end 0.12065 -0.2794)
			(stroke
				(width 0.1)
				(type default)
			)
			(layer "B.Fab")
		)
		(fp_line
			(start -0.120396 0.3048)
			(end -0.120396 0.2794)
			(stroke
				(width 0.1)
				(type default)
			)
			(layer "B.Fab")
		)
		(fp_line
			(start -0.120396 0.2794)
			(end 0.12065 0.2794)
			(stroke
				(width 0.1)
				(type default)
			)
			(layer "B.Fab")
		)
		(fp_line
			(start -0.12065 -0.2794)
			(end -0.12065 -0.3048)
			(stroke
				(width 0.1)
				(type default)
			)
			(layer "B.Fab")
		)
		(fp_line
			(start -0.12065 -0.3048)
			(end -0.67945 -0.3048)
			(stroke
				(width 0.1)
				(type default)
			)
			(layer "B.Fab")
		)
		(fp_line
			(start -0.67945 0.3048)
			(end -0.120396 0.3048)
			(stroke
				(width 0.1)
				(type default)
			)
			(layer "B.Fab")
		)
		(fp_line
			(start -0.67945 -0.3048)
			(end -0.67945 0.3048)
			(stroke
				(width 0.1)
				(type default)
			)
			(layer "B.Fab")
		)
		(pad "1" smd circle
			(at 0.40005 0)
			(size 0 0)
			(layers "B.Cu" "B.Mask" "B.Paste")
			(net "PVDD18_S5_P0")
		)
		(pad "2" smd circle
			(at -0.40005 0)
			(size 0 0)
			(layers "B.Cu" "B.Mask" "B.Paste")
			(net "SVID_PVDDCR_CPU1_P0_SVTO")
		)
	)
	(footprint ""
		(layer "B.Cu")
		(at 322.583556 -395.148562 90)
		(property "Reference" "C577"
			(at 0 0 90)
			(layer "B.SilkS")
			(hide yes)
			(effects
				(font
					(size 1.27 1.27)
				)
				(justify mirror)
			)
		)
		(property "Value" ""
			(at 0 0 90)
			(layer "B.Fab")
			(effects
				(font
					(size 1.27 1.27)
				)
				(justify mirror)
			)
		)
		(duplicate_pad_numbers_are_jumpers no)
		(fp_line
			(start 0.299974 -0.150114)
			(end -0.299974 -0.150114)
			(stroke
				(width 0.1)
				(type default)
			)
			(layer "B.Fab")
		)
		(fp_line
			(start -0.299974 -0.150114)
			(end -0.299974 0.150114)
			(stroke
				(width 0.1)
				(type default)
			)
			(layer "B.Fab")
		)
		(fp_line
			(start 0.299974 0.150114)
			(end 0.299974 -0.150114)
			(stroke
				(width 0.1)
				(type default)
			)
			(layer "B.Fab")
		)
		(fp_line
			(start -0.299974 0.150114)
			(end 0.299974 0.150114)
			(stroke
				(width 0.1)
				(type default)
			)
			(layer "B.Fab")
		)
		(pad "1" smd rect
			(at 0.2667 0 270)
			(size 0.3048 0.381)
			(layers "B.Cu" "B.Mask" "B.Paste")
			(net "P0V9_CPU0_RT0_2A")
		)
		(pad "2" smd rect
			(at -0.2667 0 270)
			(size 0.3048 0.381)
			(layers "B.Cu" "B.Mask" "B.Paste")
			(net "GND")
		)
	)
)
